FILE_TYPE = CONNECTIVITY;
{Allegro Design Entry HDL 16.6-p007 (v16-6-112F) 10/10/2012}
"PAGE_NUMBER" = 42;
0"NC";
1"GND\g";
2"GND\g";
3"GND\g";
4"PVCCIN_CPU0\g";
5"PVCCIN_CPU0\g";
6"PVCCIN_CPU0\g";
7"GND\g";
8"GND\g";
9"GND\g";
10"PVCCIN_CPU0\g";
11"PVCCIN_CPU0\g";
12"PVCCIN_CPU0\g";
13"PVCCMCP_CPU0\g";
14"PVCCMCP_CPU0\g";
15"PVCCIO_CPU0\g";
16"PVCCMCP_CPU0\g";
17"GND\g";
18"GND\g";
19"GND\g";
20"PVSA_CPU0\g";
21"GND\g";
22"GND\g";
23"GND\g";
24"PVCCIN_CPU0\g";
25"PVCCIN_CPU0\g";
26"PVCCIN_CPU0\g";
27"GND\g";
28"GND\g";
29"GND\g";
30"GND\g";
31"PVCCIN_CPU0\g";
32"PVCCIN_CPU0\g";
33"PVCCIN_CPU0\g";
34"GND\g";
35"GND\g";
36"PVCCIO_CPU0\g";
37"GND\g";
38"PVSA_CPU0\g";
%"CAP"
"1","(-2550,950)","0","mstr_discrete","I10";
;
ROOM"PVCCIN_CPU0_DECAP_VR"
CDS_LOCATION"C4P1"
$SEC"1"
CDS_SEC"1"
CDS_LIB"mstr_discrete"
BOM_COST"PROC_SOCKET"
MATERIAL"X6S"
VOLTAGE"4V"
PACK_TYPE"0805"
TOLERANCE"20%"
VALUE"47UF"
PART_NUMBER"C95333-006"
LOCATION"C4P1";
"A"
$PN"1"15;
"B"
$PN"2"18;
%"CAP_A"
"1","(-4700,3775)","0","dev_discrete","I100";
;
ROOM"PVCCIN_CPU0_DECAP_VR"
$SEC"1"
CDS_SEC"1"
CDS_LIB"dev_discrete"
BOM_COST"PROC_SOCKET"
CDS_LOCATION"C5D28"
MATERIAL"X6S"
VOLTAGE"4V"
PACK_TYPE"0603V"
TOLERANCE"20%"
VALUE"22.0UF"
PART_NUMBER"E15431-004"
LOCATION"C5D28";
"B"
$PN"2"1;
"A"
$PN"1"5;
%"GND"
"1","(-4425,3475)","0","mstr_symbols","I101";
;
HDL_POWER"GND"
BODY_TYPE"PLUMBING"
SIZE"1B"
CDS_LIB"mstr_symbols"
VOLTAGE"0";
"A\NAC"1;
%"CAP_A"
"1","(-4700,4450)","0","dev_discrete","I102";
;
ROOM"PVCCIN_CPU0_DECAP_VR"
$SEC"1"
CDS_SEC"1"
CDS_LIB"dev_discrete"
BOM_COST"PROC_SOCKET"
CDS_LOCATION"C5D29"
MATERIAL"X6S"
VOLTAGE"4V"
PACK_TYPE"0603V"
TOLERANCE"20%"
VALUE"22.0UF"
PART_NUMBER"E15431-004"
LOCATION"C5D29";
"B"
$PN"2"2;
"A"
$PN"1"4;
%"CAP_A"
"1","(-5000,4475)","0","dev_discrete","I103";
;
ROOM"PVCCIN_CPU0_DECAP_VR"
$SEC"1"
CDS_SEC"1"
CDS_LIB"dev_discrete"
BOM_COST"PROC_SOCKET"
CDS_LOCATION"C5D32"
MATERIAL"X6S"
VOLTAGE"4V"
PACK_TYPE"0603V"
TOLERANCE"20%"
VALUE"22.0UF"
PART_NUMBER"E15431-004"
LOCATION"C5D32";
"B"
$PN"2"2;
"A"
$PN"1"4;
%"CAP_A"
"1","(-5325,4475)","0","dev_discrete","I104";
;
ROOM"PVCCIN_CPU0_DECAP_VR"
$SEC"1"
CDS_SEC"1"
CDS_LIB"dev_discrete"
BOM_COST"PROC_SOCKET"
CDS_LOCATION"C5D47"
MATERIAL"X6S"
VOLTAGE"4V"
PACK_TYPE"0603V"
TOLERANCE"20%"
VALUE"22.0UF"
PART_NUMBER"E15431-004"
LOCATION"C5D47";
"B"
$PN"2"2;
"A"
$PN"1"4;
%"GND"
"1","(-4450,4150)","0","mstr_symbols","I105";
;
HDL_POWER"GND"
BODY_TYPE"PLUMBING"
CDS_LIB"mstr_symbols"
SIZE"1B"
VOLTAGE"0";
"A\NAC"2;
%"CAP_A"
"1","(-5000,3775)","0","dev_discrete","I106";
;
ROOM"PVCCIN_CPU0_DECAP_VR"
$SEC"1"
CDS_SEC"1"
CDS_LIB"dev_discrete"
BOM_COST"PROC_SOCKET"
CDS_LOCATION"C5D31"
MATERIAL"X6S"
VOLTAGE"4V"
PACK_TYPE"0603V"
TOLERANCE"20%"
VALUE"22.0UF"
PART_NUMBER"E15431-004"
LOCATION"C5D31";
"B"
$PN"2"1;
"A"
$PN"1"5;
%"CAP_A"
"1","(-5325,3800)","0","dev_discrete","I107";
;
ROOM"PVCCIN_CPU0_DECAP_VR"
$SEC"1"
CDS_SEC"1"
CDS_LIB"dev_discrete"
BOM_COST"PROC_SOCKET"
CDS_LOCATION"C5D46"
MATERIAL"X6S"
VOLTAGE"4V"
PACK_TYPE"0603V"
TOLERANCE"20%"
VALUE"22.0UF"
PART_NUMBER"E15431-004"
LOCATION"C5D46";
"B"
$PN"2"1;
"A"
$PN"1"5;
%"CAP"
"1","(-4075,3125)","0","mstr_discrete","I108";
;
ROOM"PVCCIN_CPU0_DECAP_VR"
CDS_LOCATION"C5D10"
$SEC"1"
CDS_SEC"1"
CDS_LIB"mstr_discrete"
BOM_COST"PROC_SOCKET"
MATERIAL"X6S"
VOLTAGE"4V"
PACK_TYPE"0603LF"
TOLERANCE"20%"
VALUE"10UF"
PART_NUMBER"E15431-001"
LOCATION"C5D10";
"A"
$PN"1"38;
"B"
$PN"2"37;
%"CAP_A"
"1","(-4750,3175)","0","dev_discrete","I109";
;
ROOM"PVCCIN_CPU0_DECAP_VR"
$SEC"1"
CDS_SEC"1"
CDS_LIB"dev_discrete"
BOM_COST"PROC_SOCKET"
CDS_LOCATION"C5D27"
MATERIAL"X6S"
VOLTAGE"4V"
PACK_TYPE"0603V"
TOLERANCE"20%"
VALUE"22.0UF"
PART_NUMBER"E15431-004"
LOCATION"C5D27";
"B"
$PN"2"3;
"A"
$PN"1"6;
%"GND"
"1","(-4450,2850)","0","mstr_symbols","I110";
;
HDL_POWER"GND"
BODY_TYPE"PLUMBING"
CDS_LIB"mstr_symbols"
SIZE"1B"
VOLTAGE"0";
"A\NAC"3;
%"CAP_A"
"1","(-5075,3150)","0","dev_discrete","I111";
;
ROOM"PVCCIN_CPU0_DECAP_VR"
$SEC"1"
CDS_SEC"1"
CDS_LIB"dev_discrete"
BOM_COST"PROC_SOCKET"
CDS_LOCATION"C5D30"
MATERIAL"X6S"
VOLTAGE"4V"
PACK_TYPE"0603V"
TOLERANCE"20%"
VALUE"22.0UF"
PART_NUMBER"E15431-004"
LOCATION"C5D30";
"B"
$PN"2"3;
"A"
$PN"1"6;
%"CAP_A"
"1","(-5350,3150)","0","dev_discrete","I112";
;
ROOM"PVCCIN_CPU0_DECAP_VR"
$SEC"1"
CDS_SEC"1"
CDS_LIB"dev_discrete"
BOM_COST"PROC_SOCKET"
CDS_LOCATION"C5D60"
MATERIAL"X6S"
VOLTAGE"4V"
PACK_TYPE"0603V"
TOLERANCE"20%"
VALUE"22.0UF"
PART_NUMBER"E15431-004"
LOCATION"C5D60";
"B"
$PN"2"3;
"A"
$PN"1"6;
%"CAP_A"
"1","(-5625,3175)","0","dev_discrete","I113";
;
ROOM"PVCCIN_CPU0_DECAP_VR"
$SEC"1"
CDS_SEC"1"
CDS_LIB"dev_discrete"
BOM_COST"PROC_SOCKET"
CDS_LOCATION"C5D61"
MATERIAL"X6S"
VOLTAGE"4V"
PACK_TYPE"0603V"
TOLERANCE"20%"
VALUE"22.0UF"
PART_NUMBER"E15431-004"
LOCATION"C5D61";
"B"
$PN"2"3;
"A"
$PN"1"6;
%"CAP_A"
"1","(-5625,3800)","0","dev_discrete","I114";
;
ROOM"PVCCIN_CPU0_DECAP_VR"
$SEC"1"
CDS_SEC"1"
CDS_LIB"dev_discrete"
BOM_COST"PROC_SOCKET"
CDS_LOCATION"C5D41"
MATERIAL"X6S"
VOLTAGE"4V"
PACK_TYPE"0603V"
TOLERANCE"20%"
VALUE"22.0UF"
PART_NUMBER"E15431-004"
LOCATION"C5D41";
"B"
$PN"2"1;
"A"
$PN"1"5;
%"CAP_A"
"1","(-5625,4475)","0","dev_discrete","I115";
;
ROOM"PVCCIN_CPU0_DECAP_VR"
$SEC"1"
CDS_SEC"1"
CDS_LIB"dev_discrete"
BOM_COST"PROC_SOCKET"
CDS_LOCATION"C5D40"
MATERIAL"X6S"
VOLTAGE"4V"
PACK_TYPE"0603V"
TOLERANCE"20%"
VALUE"22.0UF"
PART_NUMBER"E15431-004"
LOCATION"C5D40";
"B"
$PN"2"2;
"A"
$PN"1"4;
%"PVCCIN_CPU0"
"1","(-5950,4750)","0","mstr_symbols","I116";
;
HDL_POWER"PVCCIN_CPU0"
BODY_TYPE"PLUMBING"
CDS_LIB"mstr_symbols"
VOLTAGE"2.0V";
"G\NAC"4;
%"CAP_A"
"1","(-5950,4475)","0","dev_discrete","I117";
;
ROOM"PVCCIN_CPU0_DECAP_VR"
$SEC"1"
CDS_SEC"1"
CDS_LIB"dev_discrete"
BOM_COST"PROC_SOCKET"
CDS_LOCATION"C5D14"
MATERIAL"X6S"
VOLTAGE"4V"
PACK_TYPE"0603V"
TOLERANCE"20%"
VALUE"22.0UF"
PART_NUMBER"E15431-004"
LOCATION"C5D14";
"B"
$PN"2"2;
"A"
$PN"1"4;
%"CAP_A"
"1","(-6350,4475)","0","dev_discrete","I118";
;
ROOM"PVCCIN_CPU0_DECAP_VR"
$SEC"1"
CDS_SEC"1"
CDS_LIB"dev_discrete"
BOM_COST"PROC_SOCKET"
CDS_LOCATION"C5D17"
MATERIAL"X6S"
VOLTAGE"4V"
PACK_TYPE"0603V"
TOLERANCE"20%"
VALUE"22.0UF"
PART_NUMBER"E15431-004"
LOCATION"C5D17";
"B"
$PN"2"7;
"A"
$PN"1"10;
%"PVCCIN_CPU0"
"1","(-5925,4075)","0","mstr_symbols","I119";
;
HDL_POWER"PVCCIN_CPU0"
BODY_TYPE"PLUMBING"
CDS_LIB"mstr_symbols"
VOLTAGE"2.0V";
"G\NAC"5;
%"CAP"
"1","(-2850,950)","0","mstr_discrete","I12";
;
ROOM"PVCCIN_CPU0_DECAP_VR"
CDS_LOCATION"C4P9"
$SEC"1"
CDS_SEC"1"
CDS_LIB"mstr_discrete"
BOM_COST"PROC_SOCKET"
MATERIAL"X6S"
VOLTAGE"4V"
PACK_TYPE"0805"
TOLERANCE"20%"
VALUE"47UF"
PART_NUMBER"C95333-006"
LOCATION"C4P9";
"A"
$PN"1"15;
"B"
$PN"2"18;
%"CAP_A"
"1","(-5925,3800)","0","dev_discrete","I120";
;
ROOM"PVCCIN_CPU0_DECAP_VR"
$SEC"1"
CDS_SEC"1"
CDS_LIB"dev_discrete"
BOM_COST"PROC_SOCKET"
CDS_LOCATION"C5D58"
MATERIAL"X6S"
VOLTAGE"4V"
PACK_TYPE"0603V"
TOLERANCE"20%"
VALUE"22.0UF"
PART_NUMBER"E15431-004"
LOCATION"C5D58";
"B"
$PN"2"1;
"A"
$PN"1"5;
%"PVCCIN_CPU0"
"1","(-5900,3450)","0","mstr_symbols","I121";
;
HDL_POWER"PVCCIN_CPU0"
BODY_TYPE"PLUMBING"
CDS_LIB"mstr_symbols"
VOLTAGE"2.0V";
"G\NAC"6;
%"GND"
"1","(-6350,4150)","0","mstr_symbols","I122";
;
HDL_POWER"GND"
BODY_TYPE"PLUMBING"
CDS_LIB"mstr_symbols"
SIZE"1B"
VOLTAGE"0";
"A\NAC"7;
%"CAP_A"
"1","(-6300,3800)","0","dev_discrete","I123";
;
ROOM"PVCCIN_CPU0_DECAP_VR"
$SEC"1"
CDS_SEC"1"
CDS_LIB"dev_discrete"
BOM_COST"PROC_SOCKET"
CDS_LOCATION"C5D16"
MATERIAL"X6S"
VOLTAGE"4V"
PACK_TYPE"0603V"
TOLERANCE"20%"
VALUE"22.0UF"
PART_NUMBER"E15431-004"
LOCATION"C5D16";
"B"
$PN"2"8;
"A"
$PN"1"11;
%"GND"
"1","(-6300,3475)","0","mstr_symbols","I124";
;
HDL_POWER"GND"
BODY_TYPE"PLUMBING"
CDS_LIB"mstr_symbols"
SIZE"1B"
VOLTAGE"0";
"A\NAC"8;
%"CAP_A"
"1","(-6675,4475)","0","dev_discrete","I125";
;
ROOM"PVCCIN_CPU0_DECAP_VR"
$SEC"1"
CDS_SEC"1"
CDS_LIB"dev_discrete"
BOM_COST"PROC_SOCKET"
CDS_LOCATION"C5D5"
MATERIAL"X6S"
VOLTAGE"4V"
PACK_TYPE"0603V"
TOLERANCE"20%"
VALUE"22.0UF"
PART_NUMBER"E15431-004"
LOCATION"C5D5";
"B"
$PN"2"7;
"A"
$PN"1"10;
%"CAP_A"
"1","(-7050,4475)","0","dev_discrete","I126";
;
ROOM"PVCCIN_CPU0_DECAP_VR"
$SEC"1"
CDS_SEC"1"
CDS_LIB"dev_discrete"
BOM_COST"PROC_SOCKET"
CDS_LOCATION"C5D1"
MATERIAL"X6S"
VOLTAGE"4V"
PACK_TYPE"0603V"
TOLERANCE"20%"
VALUE"22.0UF"
PART_NUMBER"E15431-004"
LOCATION"C5D1";
"B"
$PN"2"7;
"A"
$PN"1"10;
%"CAP_A"
"1","(-7375,4475)","0","dev_discrete","I127";
;
ROOM"PVCCIN_CPU0_DECAP_VR"
$SEC"1"
CDS_SEC"1"
CDS_LIB"dev_discrete"
BOM_COST"PROC_SOCKET"
CDS_LOCATION"C5D4"
MATERIAL"X6S"
VOLTAGE"4V"
PACK_TYPE"0603V"
TOLERANCE"20%"
VALUE"22.0UF"
PART_NUMBER"E15431-004"
LOCATION"C5D4";
"B"
$PN"2"7;
"A"
$PN"1"10;
%"CAP_A"
"1","(-6650,3800)","0","dev_discrete","I128";
;
ROOM"PVCCIN_CPU0_DECAP_VR"
$SEC"1"
CDS_SEC"1"
CDS_LIB"dev_discrete"
BOM_COST"PROC_SOCKET"
CDS_LOCATION"C5D19"
MATERIAL"X6S"
VOLTAGE"4V"
PACK_TYPE"0603V"
TOLERANCE"20%"
VALUE"22.0UF"
PART_NUMBER"E15431-004"
LOCATION"C5D19";
"B"
$PN"2"8;
"A"
$PN"1"11;
%"CAP_A"
"1","(-7000,3800)","0","dev_discrete","I129";
;
ROOM"PVCCIN_CPU0_DECAP_VR"
$SEC"1"
CDS_SEC"1"
CDS_LIB"dev_discrete"
BOM_COST"PROC_SOCKET"
CDS_LOCATION"C5D59"
MATERIAL"X6S"
VOLTAGE"4V"
PACK_TYPE"0603V"
TOLERANCE"20%"
VALUE"22.0UF"
PART_NUMBER"E15431-004"
LOCATION"C5D59";
"B"
$PN"2"8;
"A"
$PN"1"11;
%"CAP"
"1","(-3825,2175)","0","mstr_discrete","I13";
;
ROOM"PVCCIN_CPU0_DECAP_VR"
CDS_LOCATION"C5P19"
$SEC"1"
CDS_SEC"1"
BOM_COST"PROC_SOCKET"
CDS_LIB"mstr_discrete"
MATERIAL"X6S"
VOLTAGE"4V"
PACK_TYPE"0805"
TOLERANCE"20%"
VALUE"47UF"
PART_NUMBER"C95333-006"
LOCATION"C5P19";
"A"
$PN"1"14;
"B"
$PN"2"29;
%"CAP_A"
"1","(-7325,3800)","0","dev_discrete","I130";
;
ROOM"PVCCIN_CPU0_DECAP_VR"
$SEC"1"
CDS_SEC"1"
CDS_LIB"dev_discrete"
BOM_COST"PROC_SOCKET"
CDS_LOCATION"C5D3"
MATERIAL"X6S"
VOLTAGE"4V"
PACK_TYPE"0603V"
TOLERANCE"20%"
VALUE"22.0UF"
PART_NUMBER"E15431-004"
LOCATION"C5D3";
"B"
$PN"2"8;
"A"
$PN"1"11;
%"CAP_A"
"1","(-5900,3150)","0","dev_discrete","I131";
;
ROOM"PVCCIN_CPU0_DECAP_VR"
$SEC"1"
CDS_SEC"1"
CDS_LIB"dev_discrete"
BOM_COST"PROC_SOCKET"
CDS_LOCATION"C5D43"
MATERIAL"X6S"
VOLTAGE"4V"
PACK_TYPE"0603V"
TOLERANCE"20%"
VALUE"22.0UF"
PART_NUMBER"E15431-004"
LOCATION"C5D43";
"B"
$PN"2"3;
"A"
$PN"1"6;
%"CAP_A"
"1","(-6250,3175)","0","dev_discrete","I132";
;
ROOM"PVCCIN_CPU0_DECAP_VR"
$SEC"1"
CDS_SEC"1"
CDS_LIB"dev_discrete"
BOM_COST"PROC_SOCKET"
CDS_LOCATION"C5D15"
MATERIAL"X6S"
VOLTAGE"4V"
PACK_TYPE"0603V"
TOLERANCE"20%"
VALUE"22.0UF"
PART_NUMBER"E15431-004"
LOCATION"C5D15";
"B"
$PN"2"9;
"A"
$PN"1"12;
%"GND"
"1","(-6250,2850)","0","mstr_symbols","I133";
;
HDL_POWER"GND"
BODY_TYPE"PLUMBING"
CDS_LIB"mstr_symbols"
SIZE"1B"
VOLTAGE"0";
"A\NAC"9;
%"CAP_A"
"1","(-6600,3150)","0","dev_discrete","I134";
;
ROOM"PVCCIN_CPU0_DECAP_VR"
$SEC"1"
CDS_SEC"1"
CDS_LIB"dev_discrete"
BOM_COST"PROC_SOCKET"
CDS_LOCATION"C5D18"
MATERIAL"X6S"
VOLTAGE"4V"
PACK_TYPE"0603V"
TOLERANCE"20%"
VALUE"22.0UF"
PART_NUMBER"E15431-004"
LOCATION"C5D18";
"B"
$PN"2"9;
"A"
$PN"1"12;
%"CAP_A"
"1","(-6950,3175)","0","dev_discrete","I135";
;
ROOM"PVCCIN_CPU0_DECAP_VR"
$SEC"1"
CDS_SEC"1"
CDS_LIB"dev_discrete"
BOM_COST"PROC_SOCKET"
CDS_LOCATION"C5D42"
MATERIAL"X6S"
VOLTAGE"4V"
PACK_TYPE"0603V"
TOLERANCE"20%"
VALUE"22.0UF"
PART_NUMBER"E15431-004"
LOCATION"C5D42";
"B"
$PN"2"9;
"A"
$PN"1"12;
%"CAP_A"
"1","(-7275,3175)","0","dev_discrete","I136";
;
ROOM"PVCCIN_CPU0_DECAP_VR"
$SEC"1"
CDS_SEC"1"
CDS_LIB"dev_discrete"
BOM_COST"PROC_SOCKET"
CDS_LOCATION"C5D2"
MATERIAL"X6S"
VOLTAGE"4V"
PACK_TYPE"0603V"
TOLERANCE"20%"
VALUE"22.0UF"
PART_NUMBER"E15431-004"
LOCATION"C5D2";
"B"
$PN"2"9;
"A"
$PN"1"12;
%"PVCCIN_CPU0"
"1","(-7725,4750)","0","mstr_symbols","I137";
;
HDL_POWER"PVCCIN_CPU0"
BODY_TYPE"PLUMBING"
CDS_LIB"mstr_symbols"
VOLTAGE"2.0V";
"G\NAC"10;
%"CAP_A"
"1","(-7725,4475)","0","dev_discrete","I138";
;
ROOM"PVCCIN_CPU0_DECAP_VR"
$SEC"1"
CDS_SEC"1"
CDS_LIB"dev_discrete"
BOM_COST"PROC_SOCKET"
CDS_LOCATION"C5D24"
MATERIAL"X6S"
VOLTAGE"4V"
PACK_TYPE"0603V"
TOLERANCE"20%"
VALUE"22.0UF"
PART_NUMBER"E15431-004"
LOCATION"C5D24";
"B"
$PN"2"7;
"A"
$PN"1"10;
%"PVCCIN_CPU0"
"1","(-7675,4075)","0","mstr_symbols","I139";
;
HDL_POWER"PVCCIN_CPU0"
BODY_TYPE"PLUMBING"
CDS_LIB"mstr_symbols"
VOLTAGE"2.0V";
"G\NAC"11;
%"CAP"
"1","(-4100,2175)","0","mstr_discrete","I14";
;
ROOM"PVCCIN_CPU0_DECAP_VR"
CDS_LOCATION"C4P4"
$SEC"1"
CDS_SEC"1"
BOM_COST"PROC_SOCKET"
CDS_LIB"mstr_discrete"
MATERIAL"X6S"
VOLTAGE"4V"
PACK_TYPE"0805"
TOLERANCE"20%"
VALUE"47UF"
PART_NUMBER"C95333-006"
LOCATION"C4P4";
"A"
$PN"1"14;
"B"
$PN"2"29;
%"CAP_A"
"1","(-7675,3800)","0","dev_discrete","I140";
;
ROOM"PVCCIN_CPU0_DECAP_VR"
$SEC"1"
CDS_SEC"1"
CDS_LIB"dev_discrete"
BOM_COST"PROC_SOCKET"
CDS_LOCATION"C5D39"
MATERIAL"X6S"
VOLTAGE"4V"
PACK_TYPE"0603V"
TOLERANCE"20%"
VALUE"22.0UF"
PART_NUMBER"E15431-004"
LOCATION"C5D39";
"B"
$PN"2"8;
"A"
$PN"1"11;
%"PVCCIN_CPU0"
"1","(-7625,3450)","0","mstr_symbols","I141";
;
HDL_POWER"PVCCIN_CPU0"
BODY_TYPE"PLUMBING"
CDS_LIB"mstr_symbols"
VOLTAGE"2.0V";
"G\NAC"12;
%"CAP_A"
"1","(-7625,3175)","0","dev_discrete","I142";
;
ROOM"PVCCIN_CPU0_DECAP_VR"
$SEC"1"
CDS_SEC"1"
CDS_LIB"dev_discrete"
BOM_COST"PROC_SOCKET"
CDS_LOCATION"C5D44"
MATERIAL"X6S"
VOLTAGE"4V"
PACK_TYPE"0603V"
TOLERANCE"20%"
VALUE"22.0UF"
PART_NUMBER"E15431-004"
LOCATION"C5D44";
"B"
$PN"2"9;
"A"
$PN"1"12;
%"VCC_CORE"
"1","(-3875,4750)","0","mstr_symbols","I144";
;
CDS_LIB"mstr_symbols"
HDL_POWER"PVCCMCP_CPU0";
"A"13;
%"CAP_A"
"1","(-2850,3775)","0","dev_discrete","I145";
;
ROOM"PVCCIN_CPU0_DECAP_VR"
$SEC"1"
CDS_SEC"1"
CDS_LIB"dev_discrete"
CDS_LOCATION"C6D9"
MATERIAL"X6S"
VOLTAGE"4V"
PACK_TYPE"0603V"
TOLERANCE"20%"
VALUE"22.0UF"
PART_NUMBER"E15431-004"
LOCATION"C6D9";
"B"
$PN"2"35;
"A"
$PN"1"36;
%"CAP_A"
"1","(-3125,3775)","0","dev_discrete","I147";
;
ROOM"PVCCIN_CPU0_DECAP_VR"
$SEC"1"
CDS_SEC"1"
CDS_LIB"dev_discrete"
CDS_LOCATION"C6D10"
MATERIAL"X6S"
VOLTAGE"4V"
PACK_TYPE"0603V"
TOLERANCE"20%"
VALUE"22.0UF"
PART_NUMBER"E15431-004"
LOCATION"C6D10";
"B"
$PN"2"35;
"A"
$PN"1"36;
%"CAP"
"1","(-4425,2175)","0","mstr_discrete","I148";
;
ROOM"PVCCIN_CPU0_DECAP_VR"
CDS_LOCATION"C5P30"
$SEC"1"
CDS_SEC"1"
CDS_LIB"mstr_discrete"
MATERIAL"X6S"
VOLTAGE"4V"
PACK_TYPE"0805"
TOLERANCE"20%"
VALUE"47UF"
PART_NUMBER"C95333-006"
LOCATION"C5P30";
"A"
$PN"1"14;
"B"
$PN"2"29;
%"CAP"
"1","(-4675,2175)","0","mstr_discrete","I149";
;
ROOM"PVCCIN_CPU0_DECAP_VR"
CDS_LOCATION"C5P29"
$SEC"1"
CDS_SEC"1"
CDS_LIB"mstr_discrete"
MATERIAL"X6S"
VOLTAGE"4V"
PACK_TYPE"0805"
TOLERANCE"20%"
VALUE"47UF"
PART_NUMBER"C95333-006"
LOCATION"C5P29";
"A"
$PN"1"14;
"B"
$PN"2"29;
%"CAP_A"
"1","(-2575,4475)","0","dev_discrete","I151";
;
ROOM"PVCCIN_CPU0_DECAP_VR"
$SEC"1"
CDS_SEC"1"
CDS_LIB"dev_discrete"
BOM_COST"PROC_SOCKET"
CDS_LOCATION"C5D36"
MATERIAL"X6S"
VOLTAGE"4V"
PACK_TYPE"0603V"
TOLERANCE"20%"
VALUE"22.0UF"
PART_NUMBER"E15431-004"
LOCATION"C5D36";
"B"
$PN"2"34;
"A"
$PN"1"13;
%"CAP_A"
"1","(-2275,4450)","0","dev_discrete","I152";
;
ROOM"PVCCIN_CPU0_DECAP_VR"
$SEC"1"
CDS_SEC"1"
CDS_LIB"dev_discrete"
BOM_COST"PROC_SOCKET"
CDS_LOCATION"C5D49"
MATERIAL"X6S"
VOLTAGE"4V"
PACK_TYPE"0603V"
TOLERANCE"20%"
VALUE"22.0UF"
PART_NUMBER"E15431-004"
LOCATION"C5D49";
"B"
$PN"2"34;
"A"
$PN"1"13;
%"CAP_A"
"1","(-525,4475)","0","dev_discrete","I153";
;
ROOM"PVCCIN_CPU0_DECAP_VR"
$SEC"1"
CDS_SEC"1"
CDS_LIB"dev_discrete"
BOM_COST"PROC_SOCKET"
CDS_LOCATION"C5D22"
MATERIAL"X6S"
VOLTAGE"4V"
PACK_TYPE"0603V"
TOLERANCE"20%"
VALUE"22.0UF"
PART_NUMBER"E15431-004"
LOCATION"C5D22";
"B"
$PN"2"34;
"A"
$PN"1"13;
%"CAP_A"
"1","(-4450,4475)","0","dev_discrete","I154";
;
ROOM"PVCCIN_CPU0_DECAP_VR"
$SEC"1"
CDS_SEC"1"
CDS_LIB"dev_discrete"
BOM_COST"PROC_SOCKET"
CDS_LOCATION"C5D26"
MATERIAL"X6S"
VOLTAGE"4V"
PACK_TYPE"0603V"
TOLERANCE"20%"
VALUE"22.0UF"
PART_NUMBER"E15431-004"
LOCATION"C5D26";
"B"
$PN"2"2;
"A"
$PN"1"4;
%"CAP_A"
"1","(-4425,3800)","0","dev_discrete","I155";
;
ROOM"PVCCIN_CPU0_DECAP_VR"
$SEC"1"
CDS_SEC"1"
CDS_LIB"dev_discrete"
BOM_COST"PROC_SOCKET"
CDS_LOCATION"C5D25"
MATERIAL"X6S"
VOLTAGE"4V"
PACK_TYPE"0603V"
TOLERANCE"20%"
VALUE"22.0UF"
PART_NUMBER"E15431-004"
LOCATION"C5D25";
"B"
$PN"2"1;
"A"
$PN"1"5;
%"CAP_A"
"1","(-4450,3200)","0","dev_discrete","I156";
;
ROOM"PVCCIN_CPU0_DECAP_VR"
$SEC"1"
CDS_SEC"1"
CDS_LIB"dev_discrete"
BOM_COST"PROC_SOCKET"
CDS_LOCATION"C5D45"
MATERIAL"X6S"
VOLTAGE"4V"
PACK_TYPE"0603V"
TOLERANCE"20%"
VALUE"22.0UF"
PART_NUMBER"E15431-004"
LOCATION"C5D45";
"B"
$PN"2"3;
"A"
$PN"1"6;
%"VCC_CORE"
"1","(-4675,2525)","0","mstr_symbols","I159";
;
CDS_LIB"mstr_symbols"
HDL_POWER"PVCCMCP_CPU0";
"A"14;
%"PVCCIO_CPU0"
"1","(-3175,1250)","0","mstr_symbols","I16";
;
HDL_POWER"PVCCIO_CPU0"
BODY_TYPE"PLUMBING"
CDS_LIB"mstr_symbols"
VOLTAGE"1.1V";
"G\NAC"15;
%"CAP"
"1","(-1900,2150)","0","mstr_discrete","I162";
;
ROOM"PVCCIN_CPU0_DECAP_VR"
CDS_LOCATION"C5P31"
$SEC"1"
CDS_SEC"1"
CDS_LIB"mstr_discrete"
LOCATION"C5P31"
PART_NUMBER"C95333-006"
MATERIAL"X6S"
VOLTAGE"4V"
PACK_TYPE"0805"
TOLERANCE"20%"
VALUE"47UF";
"A"
$PN"1"14;
"B"
$PN"2"29;
%"CAP"
"1","(-1650,2150)","0","mstr_discrete","I163";
;
ROOM"PVCCIN_CPU0_DECAP_VR"
CDS_LOCATION"C4P2"
$SEC"1"
CDS_SEC"1"
CDS_LIB"mstr_discrete"
MATERIAL"X6S"
VOLTAGE"4V"
PACK_TYPE"0805"
TOLERANCE"20%"
VALUE"47UF"
PART_NUMBER"C95333-006"
LOCATION"C4P2";
"A"
$PN"1"14;
"B"
$PN"2"29;
%"CAP_A"
"1","(-2250,950)","0","dev_discrete","I164";
;
ROOM"PVCCIN_CPU0_DECAP_VR"
$SEC"1"
CDS_SEC"1"
CDS_LIB"dev_discrete"
CDS_LOCATION"C4P6"
MATERIAL"X6S"
VOLTAGE"4V"
PACK_TYPE"0603V"
TOLERANCE"20%"
VALUE"22.0UF"
PART_NUMBER"E15431-004"
LOCATION"C4P6";
"B"
$PN"2"18;
"A"
$PN"1"15;
%"CAP"
"1","(-3175,950)","0","mstr_discrete","I17";
;
ROOM"PVCCIN_CPU0_DECAP_VR"
CDS_LOCATION"C4P10"
$SEC"1"
CDS_SEC"1"
CDS_LIB"mstr_discrete"
BOM_COST"PROC_SOCKET"
VOLTAGE"4V"
MATERIAL"X6S"
PACK_TYPE"0805"
TOLERANCE"20%"
VALUE"47UF"
PART_NUMBER"C95333-006"
LOCATION"C4P10";
"A"
$PN"1"15;
"B"
$PN"2"18;
%"CAP"
"1","(-1400,2150)","0","mstr_discrete","I172";
;
ROOM"PVCCIN_CPU0_DECAP_VR"
CDS_LOCATION"C4P5"
$SEC"1"
CDS_SEC"1"
CDS_LIB"mstr_discrete"
MATERIAL"X6S"
VOLTAGE"4V"
PACK_TYPE"0805"
TOLERANCE"20%"
VALUE"47UF"
PART_NUMBER"C95333-006"
LOCATION"C4P5";
"A"
$PN"1"14;
"B"
$PN"2"29;
%"CAP_A"
"1","(-1375,3850)","0","dev_discrete","I173";
;
ROOM"PVCCIN_CPU0_DECAP_VR"
$SEC"1"
CDS_SEC"1"
CDS_LIB"dev_discrete"
BOM_COST"PROC_SOCKET"
CDS_LOCATION"C5D20"
MATERIAL"X6S"
VOLTAGE"4V"
PACK_TYPE"0603V"
TOLERANCE"20%"
VALUE"22.0UF"
PART_NUMBER"E15431-004"
LOCATION"C5D20";
"B"
$PN"2"17;
"A"
$PN"1"16;
%"CAP_A"
"1","(-975,3825)","0","dev_discrete","I174";
;
ROOM"PVCCIN_CPU0_DECAP_VR"
$SEC"1"
CDS_SEC"1"
CDS_LIB"dev_discrete"
BOM_COST"PROC_SOCKET"
CDS_LOCATION"C5D33"
MATERIAL"X6S"
VOLTAGE"4V"
PACK_TYPE"0603V"
TOLERANCE"20%"
VALUE"22.0UF"
PART_NUMBER"E15431-004"
LOCATION"C5D33";
"B"
$PN"2"17;
"A"
$PN"1"16;
%"CAP_A"
"1","(-600,3800)","0","dev_discrete","I175";
;
ROOM"PVCCIN_CPU0_DECAP_VR"
$SEC"1"
CDS_SEC"1"
CDS_LIB"dev_discrete"
BOM_COST"PROC_SOCKET"
CDS_LOCATION"C5D34"
MATERIAL"X6S"
VOLTAGE"4V"
PACK_TYPE"0603V"
TOLERANCE"20%"
VALUE"22.0UF"
PART_NUMBER"E15431-004"
LOCATION"C5D34";
"B"
$PN"2"17;
"A"
$PN"1"16;
%"CAP_A"
"1","(-1700,3850)","0","dev_discrete","I176";
;
ROOM"PVCCIN_CPU0_DECAP_VR"
$SEC"1"
CDS_SEC"1"
CDS_LIB"dev_discrete"
BOM_COST"PROC_SOCKET"
CDS_LOCATION"C5D35"
MATERIAL"X6S"
VOLTAGE"4V"
PACK_TYPE"0603V"
TOLERANCE"20%"
VALUE"22.0UF"
PART_NUMBER"E15431-004"
LOCATION"C5D35";
"B"
$PN"2"17;
"A"
$PN"1"16;
%"CAP_A"
"1","(-1950,950)","0","dev_discrete","I178";
;
ROOM"PVCCIN_CPU0_DECAP_VR"
$SEC"1"
CDS_SEC"1"
CDS_LIB"dev_discrete"
CDS_LOCATION"C4P8"
MATERIAL"X6S"
VOLTAGE"4V"
PACK_TYPE"0603V"
TOLERANCE"20%"
VALUE"22.0UF"
PART_NUMBER"E15431-004"
LOCATION"C4P8";
"B"
$PN"2"18;
"A"
$PN"1"15;
%"CAP_A"
"1","(-2150,3850)","0","dev_discrete","I179";
;
ROOM"PVCCIN_CPU0_DECAP_VR"
$SEC"1"
CDS_SEC"1"
CDS_LIB"dev_discrete"
CDS_LOCATION"C5D53"
MATERIAL"X6S"
VOLTAGE"4V"
PACK_TYPE"0603V"
TOLERANCE"20%"
VALUE"22.0UF"
PART_NUMBER"E15431-004"
LOCATION"C5D53";
"B"
$PN"2"17;
"A"
$PN"1"16;
%"CAP"
"1","(-3600,975)","0","mstr_discrete","I18";
;
ROOM"PVCCIN_CPU0_DECAP_VR"
CDS_LOCATION"C5P9"
$SEC"1"
CDS_SEC"1"
BOM_COST"PROC_SOCKET"
CDS_LIB"mstr_discrete"
MATERIAL"X6S"
VOLTAGE"4V"
PACK_TYPE"0805LF"
TOLERANCE"20%"
VALUE"22UF"
PART_NUMBER"C95333-002"
LOCATION"C5P9";
"A"
$PN"1"20;
"B"
$PN"2"19;
%"CAP_A"
"1","(-2525,3825)","0","dev_discrete","I180";
;
ROOM"PVCCIN_CPU0_DECAP_VR"
$SEC"1"
CDS_SEC"1"
CDS_LIB"dev_discrete"
CDS_LOCATION"C5D52"
MATERIAL"X6S"
VOLTAGE"4V"
PACK_TYPE"0603V"
TOLERANCE"20%"
VALUE"22.0UF"
PART_NUMBER"E15431-004"
LOCATION"C5D52";
"B"
$PN"2"17;
"A"
$PN"1"16;
%"VCC_CORE"
"1","(-2525,4125)","0","mstr_symbols","I181";
;
CDS_LIB"mstr_symbols"
HDL_POWER"PVCCMCP_CPU0";
"A"16;
%"GND"
"1","(-600,3475)","0","mstr_symbols","I182";
;
HDL_POWER"GND"
BODY_TYPE"PLUMBING"
CDS_LIB"mstr_symbols"
SIZE"1B"
VOLTAGE"0";
"A\NAC"17;
%"CAP"
"1","(-375,2150)","0","mstr_discrete","I183";
;
ROOM"PVCCIN_CPU0_DECAP_VR"
CDS_LOCATION"C5P12"
$SEC"1"
CDS_SEC"1"
CDS_LIB"mstr_discrete"
BOM_COST"PROC_SOCKET"
MATERIAL"X6S"
VOLTAGE"4V"
PACK_TYPE"0805"
TOLERANCE"20%"
VALUE"47UF"
PART_NUMBER"C95333-006"
LOCATION"C5P12";
"A"
$PN"1"14;
"B"
$PN"2"29;
%"CAP"
"1","(-625,2150)","0","mstr_discrete","I184";
;
ROOM"PVCCIN_CPU0_DECAP_VR"
CDS_LOCATION"C5P21"
$SEC"1"
CDS_SEC"1"
CDS_LIB"mstr_discrete"
BOM_COST"PROC_SOCKET"
MATERIAL"X6S"
VOLTAGE"4V"
PACK_TYPE"0805"
TOLERANCE"20%"
VALUE"47UF"
PART_NUMBER"C95333-006"
LOCATION"C5P21";
"A"
$PN"1"14;
"B"
$PN"2"29;
%"CAP"
"1","(-875,2150)","0","mstr_discrete","I185";
;
ROOM"PVCCIN_CPU0_DECAP_VR"
CDS_LOCATION"C5P20"
$SEC"1"
CDS_SEC"1"
CDS_LIB"mstr_discrete"
BOM_COST"PROC_SOCKET"
MATERIAL"X6S"
VOLTAGE"4V"
PACK_TYPE"0805"
TOLERANCE"20%"
VALUE"47UF"
PART_NUMBER"C95333-006"
LOCATION"C5P20";
"A"
$PN"1"14;
"B"
$PN"2"29;
%"CAP"
"1","(-1125,2150)","0","mstr_discrete","I186";
;
ROOM"PVCCIN_CPU0_DECAP_VR"
CDS_LOCATION"C5P13"
$SEC"1"
CDS_SEC"1"
BOM_COST"PROC_SOCKET"
CDS_LIB"mstr_discrete"
MATERIAL"X6S"
VOLTAGE"4V"
PACK_TYPE"0805"
TOLERANCE"20%"
VALUE"47UF"
PART_NUMBER"C95333-006"
LOCATION"C5P13";
"A"
$PN"1"14;
"B"
$PN"2"29;
%"CAP"
"1","(-6700,1575)","0","mstr_discrete","I187";
;
ROOM"PVCCIN_CPU0_DECAP_VR"
CDS_LOCATION"C5P15"
$SEC"1"
CDS_SEC"1"
CDS_LIB"mstr_discrete"
BOM_COST"PROC_SOCKET"
MATERIAL"X6S"
VOLTAGE"4V"
PACK_TYPE"0805"
TOLERANCE"20%"
VALUE"47UF"
PART_NUMBER"C95333-006"
LOCATION"C5P15";
"A"
$PN"1"32;
"B"
$PN"2"28;
%"CAP"
"1","(-6700,2225)","0","mstr_discrete","I188";
;
ROOM"PVCCIN_CPU0_DECAP_VR"
CDS_LOCATION"C5P16"
$SEC"1"
CDS_SEC"1"
CDS_LIB"mstr_discrete"
BOM_COST"PROC_SOCKET"
MATERIAL"X6S"
VOLTAGE"4V"
PACK_TYPE"0805"
TOLERANCE"20%"
VALUE"47UF"
PART_NUMBER"C95333-006"
LOCATION"C5P16";
"A"
$PN"1"31;
"B"
$PN"2"27;
%"CAP"
"1","(-7725,925)","0","mstr_discrete","I189";
;
ROOM"PVCCIN_CPU0_DECAP_VR"
CDS_LOCATION"C5P3"
$SEC"1"
CDS_SEC"1"
CDS_LIB"mstr_discrete"
BOM_COST"PROC_SOCKET"
MATERIAL"X6S"
VOLTAGE"4V"
PACK_TYPE"0805"
TOLERANCE"20%"
VALUE"47UF"
PART_NUMBER"C95333-006"
LOCATION"C5P3";
"A"
$PN"1"33;
"B"
$PN"2"30;
%"CAP"
"1","(-3925,975)","0","mstr_discrete","I19";
;
ROOM"PVCCIN_CPU0_DECAP_VR"
CDS_LOCATION"C5P8"
$SEC"1"
CDS_SEC"1"
CDS_LIB"mstr_discrete"
BOM_COST"PROC_SOCKET"
MATERIAL"X6S"
VOLTAGE"4V"
PACK_TYPE"0805LF"
TOLERANCE"20%"
VALUE"22UF"
PART_NUMBER"C95333-002"
LOCATION"C5P8";
"A"
$PN"1"20;
"B"
$PN"2"19;
%"CAP"
"1","(-6350,1575)","0","mstr_discrete","I190";
;
ROOM"PVCCIN_CPU0_DECAP_VR"
CDS_LOCATION"C5P17"
$SEC"1"
CDS_SEC"1"
CDS_LIB"mstr_discrete"
BOM_COST"PROC_SOCKET"
MATERIAL"X6S"
VOLTAGE"4V"
PACK_TYPE"0805"
TOLERANCE"20%"
VALUE"47UF"
PART_NUMBER"C95333-006"
LOCATION"C5P17";
"A"
$PN"1"32;
"B"
$PN"2"28;
%"CAP"
"1","(-2150,2150)","0","mstr_discrete","I2";
;
ROOM"PVCCIN_CPU0_DECAP_VR"
CDS_LOCATION"C5P18"
$SEC"1"
CDS_SEC"1"
BOM_COST"PROC_SOCKET"
CDS_LIB"mstr_discrete"
MATERIAL"X6S"
VOLTAGE"4V"
PACK_TYPE"0805"
TOLERANCE"20%"
VALUE"47UF"
PART_NUMBER"C95333-006"
LOCATION"C5P18";
"A"
$PN"1"14;
"B"
$PN"2"29;
%"GND"
"1","(-1950,625)","0","mstr_symbols","I20";
;
HDL_POWER"GND"
BODY_TYPE"PLUMBING"
CDS_LIB"mstr_symbols"
SIZE"1B"
VOLTAGE"0";
"A\NAC"18;
%"GND"
"1","(-3600,650)","0","mstr_symbols","I21";
;
HDL_POWER"GND"
BODY_TYPE"PLUMBING"
SIZE"1B"
CDS_LIB"mstr_symbols"
VOLTAGE"0";
"A\NAC"19;
%"PVSA_CPU0"
"1","(-4275,1250)","0","mstr_symbols","I24";
;
HDL_POWER"PVSA_CPU0"
BODY_TYPE"PLUMBING"
CDS_LIB"mstr_symbols"
VOLTAGE"1.1V";
"G\NAC"20;
%"CAP"
"1","(-4275,975)","0","mstr_discrete","I25";
;
ROOM"PVCCIN_CPU0_DECAP_VR"
CDS_LOCATION"C5P7"
$SEC"1"
CDS_SEC"1"
BOM_COST"PROC_SOCKET"
CDS_LIB"mstr_discrete"
MATERIAL"X6S"
VOLTAGE"4V"
PACK_TYPE"0805LF"
TOLERANCE"20%"
VALUE"22UF"
PART_NUMBER"C95333-002"
LOCATION"C5P7";
"A"
$PN"1"20;
"B"
$PN"2"19;
%"CAP"
"1","(-5100,2200)","0","mstr_discrete","I27";
;
ROOM"PVCCIN_CPU0_DECAP_VR"
CDS_LOCATION"C5P4"
$SEC"1"
CDS_SEC"1"
CDS_LIB"mstr_discrete"
BOM_COST"PROC_SOCKET"
MATERIAL"X6S"
VOLTAGE"4V"
PACK_TYPE"0805"
TOLERANCE"20%"
VALUE"47UF"
PART_NUMBER"C95333-006"
LOCATION"C5P4";
"A"
$PN"1"24;
"B"
$PN"2"21;
%"CAP"
"1","(-5350,2225)","0","mstr_discrete","I28";
;
ROOM"PVCCIN_CPU0_DECAP_VR"
CDS_LOCATION"C5P23"
$SEC"1"
CDS_SEC"1"
BOM_COST"PROC_SOCKET"
CDS_LIB"mstr_discrete"
MATERIAL"X6S"
VOLTAGE"4V"
PACK_TYPE"0805"
TOLERANCE"20%"
VALUE"47UF"
PART_NUMBER"C95333-006"
LOCATION"C5P23";
"A"
$PN"1"24;
"B"
$PN"2"21;
%"GND"
"1","(-5100,1875)","0","mstr_symbols","I29";
;
HDL_POWER"GND"
BODY_TYPE"PLUMBING"
CDS_LIB"mstr_symbols"
SIZE"1B"
VOLTAGE"0";
"A\NAC"21;
%"CAP"
"1","(-2425,2175)","0","mstr_discrete","I3";
;
ROOM"PVCCIN_CPU0_DECAP_VR"
CDS_LOCATION"C5P28"
$SEC"1"
CDS_SEC"1"
BOM_COST"PROC_SOCKET"
CDS_LIB"mstr_discrete"
MATERIAL"X6S"
VOLTAGE"4V"
PACK_TYPE"0805"
TOLERANCE"20%"
VALUE"47UF"
PART_NUMBER"C95333-006"
LOCATION"C5P28";
"A"
$PN"1"14;
"B"
$PN"2"29;
%"GND"
"1","(-5300,1225)","0","mstr_symbols","I32";
;
HDL_POWER"GND"
BODY_TYPE"PLUMBING"
SIZE"1B"
CDS_LIB"mstr_symbols"
VOLTAGE"0";
"A\NAC"22;
%"CAP"
"1","(-5300,1575)","0","mstr_discrete","I33";
;
ROOM"PVCCIN_CPU0_DECAP_VR"
CDS_LOCATION"C5P24"
$SEC"1"
CDS_SEC"1"
BOM_COST"PROC_SOCKET"
CDS_LIB"mstr_discrete"
MATERIAL"X6S"
VOLTAGE"4V"
PACK_TYPE"0805"
TOLERANCE"20%"
VALUE"47UF"
PART_NUMBER"C95333-006"
LOCATION"C5P24";
"A"
$PN"1"25;
"B"
$PN"2"22;
%"GND"
"1","(-5275,600)","0","mstr_symbols","I35";
;
HDL_POWER"GND"
BODY_TYPE"PLUMBING"
CDS_LIB"mstr_symbols"
SIZE"1B"
VOLTAGE"0";
"A\NAC"23;
%"CAP"
"1","(-5275,900)","0","mstr_discrete","I37";
;
ROOM"PVCCIN_CPU0_DECAP_VR"
CDS_LOCATION"C5P25"
$SEC"1"
CDS_SEC"1"
CDS_LIB"mstr_discrete"
BOM_COST"PROC_SOCKET"
MATERIAL"X6S"
VOLTAGE"4V"
PACK_TYPE"0805"
TOLERANCE"20%"
VALUE"47UF"
PART_NUMBER"C95333-006"
LOCATION"C5P25";
"A"
$PN"1"26;
"B"
$PN"2"23;
%"CAP"
"1","(-5675,2225)","0","mstr_discrete","I38";
;
ROOM"PVCCIN_CPU0_DECAP_VR"
CDS_LOCATION"C5P6"
$SEC"1"
CDS_SEC"1"
BOM_COST"PROC_SOCKET"
CDS_LIB"mstr_discrete"
MATERIAL"X6S"
VOLTAGE"4V"
PACK_TYPE"0805"
TOLERANCE"20%"
VALUE"47UF"
PART_NUMBER"C95333-006"
LOCATION"C5P6";
"A"
$PN"1"24;
"B"
$PN"2"21;
%"PVCCIN_CPU0"
"1","(-5975,2500)","0","mstr_symbols","I39";
;
HDL_POWER"PVCCIN_CPU0"
BODY_TYPE"PLUMBING"
CDS_LIB"mstr_symbols"
VOLTAGE"2.0V";
"G\NAC"24;
%"CAP"
"1","(-2700,2175)","0","mstr_discrete","I4";
;
ROOM"PVCCIN_CPU0_DECAP_VR"
CDS_LOCATION"C5P11"
$SEC"1"
CDS_SEC"1"
BOM_COST"PROC_SOCKET"
CDS_LIB"mstr_discrete"
MATERIAL"X6S"
VOLTAGE"4V"
PACK_TYPE"0805"
TOLERANCE"20%"
VALUE"47UF"
PART_NUMBER"C95333-006"
LOCATION"C5P11";
"A"
$PN"1"14;
"B"
$PN"2"29;
%"CAP"
"1","(-5975,2225)","0","mstr_discrete","I40";
;
ROOM"PVCCIN_CPU0_DECAP_VR"
CDS_LOCATION"C5P41"
$SEC"1"
CDS_SEC"1"
BOM_COST"PROC_SOCKET"
CDS_LIB"mstr_discrete"
MATERIAL"X6S"
VOLTAGE"4V"
PACK_TYPE"0805"
TOLERANCE"20%"
VALUE"47UF"
PART_NUMBER"C95333-006"
LOCATION"C5P41";
"A"
$PN"1"24;
"B"
$PN"2"21;
%"CAP"
"1","(-6350,2225)","0","mstr_discrete","I41";
;
ROOM"PVCCIN_CPU0_DECAP_VR"
CDS_LOCATION"C5P14"
$SEC"1"
CDS_SEC"1"
CDS_LIB"mstr_discrete"
BOM_COST"PROC_SOCKET"
MATERIAL"X6S"
VOLTAGE"4V"
PACK_TYPE"0805"
TOLERANCE"20%"
VALUE"47UF"
PART_NUMBER"C95333-006"
LOCATION"C5P14";
"A"
$PN"1"31;
"B"
$PN"2"27;
%"CAP"
"1","(-5625,1575)","0","mstr_discrete","I42";
;
ROOM"PVCCIN_CPU0_DECAP_VR"
CDS_LOCATION"C5P5"
$SEC"1"
CDS_SEC"1"
BOM_COST"PROC_SOCKET"
CDS_LIB"mstr_discrete"
MATERIAL"X6S"
VOLTAGE"4V"
PACK_TYPE"0805"
TOLERANCE"20%"
VALUE"47UF"
PART_NUMBER"C95333-006"
LOCATION"C5P5";
"A"
$PN"1"25;
"B"
$PN"2"22;
%"PVCCIN_CPU0"
"1","(-5975,1850)","0","mstr_symbols","I43";
;
HDL_POWER"PVCCIN_CPU0"
BODY_TYPE"PLUMBING"
CDS_LIB"mstr_symbols"
VOLTAGE"2.0V";
"G\NAC"25;
%"CAP"
"1","(-5975,1575)","0","mstr_discrete","I44";
;
ROOM"PVCCIN_CPU0_DECAP_VR"
CDS_LOCATION"C5P27"
$SEC"1"
CDS_SEC"1"
BOM_COST"PROC_SOCKET"
CDS_LIB"mstr_discrete"
MATERIAL"X6S"
VOLTAGE"4V"
PACK_TYPE"0805"
TOLERANCE"20%"
VALUE"47UF"
LOCATION"C5P27"
PART_NUMBER"C95333-006";
"A"
$PN"1"25;
"B"
$PN"2"22;
%"PVCCIN_CPU0"
"1","(-5950,1175)","0","mstr_symbols","I45";
;
HDL_POWER"PVCCIN_CPU0"
BODY_TYPE"PLUMBING"
CDS_LIB"mstr_symbols"
VOLTAGE"2.0V";
"G\NAC"26;
%"GND"
"1","(-6350,1900)","0","mstr_symbols","I46";
;
HDL_POWER"GND"
BODY_TYPE"PLUMBING"
SIZE"1B"
CDS_LIB"mstr_symbols"
VOLTAGE"0";
"A\NAC"27;
%"GND"
"1","(-6350,1250)","0","mstr_symbols","I48";
;
HDL_POWER"GND"
BODY_TYPE"PLUMBING"
SIZE"1B"
CDS_LIB"mstr_symbols"
VOLTAGE"0";
"A\NAC"28;
%"GND"
"1","(-375,1775)","0","mstr_symbols","I5";
;
HDL_POWER"GND"
BODY_TYPE"PLUMBING"
SIZE"1B"
CDS_LIB"mstr_symbols"
VOLTAGE"0";
"A\NAC"29;
%"CAP"
"1","(-7050,2225)","0","mstr_discrete","I50";
;
ROOM"PVCCIN_CPU0_DECAP_VR"
CDS_LOCATION"C5P33"
$SEC"1"
CDS_SEC"1"
CDS_LIB"mstr_discrete"
BOM_COST"PROC_SOCKET"
MATERIAL"X6S"
VOLTAGE"4V"
PACK_TYPE"0805"
TOLERANCE"20%"
VALUE"47UF"
PART_NUMBER"C95333-006"
LOCATION"C5P33";
"A"
$PN"1"31;
"B"
$PN"2"27;
%"CAP"
"1","(-7375,2225)","0","mstr_discrete","I51";
;
ROOM"PVCCIN_CPU0_DECAP_VR"
CDS_LOCATION"C5P35"
$SEC"1"
CDS_SEC"1"
CDS_LIB"mstr_discrete"
BOM_COST"PROC_SOCKET"
MATERIAL"X6S"
VOLTAGE"4V"
PACK_TYPE"0805"
TOLERANCE"20%"
VALUE"47UF"
PART_NUMBER"C95333-006"
LOCATION"C5P35";
"A"
$PN"1"31;
"B"
$PN"2"27;
%"CAP"
"1","(-7050,1575)","0","mstr_discrete","I53";
;
ROOM"PVCCIN_CPU0_DECAP_VR"
CDS_LOCATION"C5P32"
$SEC"1"
CDS_SEC"1"
CDS_LIB"mstr_discrete"
BOM_COST"PROC_SOCKET"
MATERIAL"X6S"
VOLTAGE"4V"
PACK_TYPE"0805"
TOLERANCE"20%"
VALUE"47UF"
PART_NUMBER"C95333-006"
LOCATION"C5P32";
"A"
$PN"1"32;
"B"
$PN"2"28;
%"CAP"
"1","(-7375,1575)","0","mstr_discrete","I54";
;
ROOM"PVCCIN_CPU0_DECAP_VR"
CDS_LOCATION"C5P34"
$SEC"1"
CDS_SEC"1"
CDS_LIB"mstr_discrete"
BOM_COST"PROC_SOCKET"
MATERIAL"X6S"
VOLTAGE"4V"
PACK_TYPE"0805"
TOLERANCE"20%"
VALUE"47UF"
PART_NUMBER"C95333-006"
LOCATION"C5P34";
"A"
$PN"1"32;
"B"
$PN"2"28;
%"CAP"
"1","(-5600,900)","0","mstr_discrete","I55";
;
ROOM"PVCCIN_CPU0_DECAP_VR"
CDS_LOCATION"C5P22"
$SEC"1"
CDS_SEC"1"
CDS_LIB"mstr_discrete"
BOM_COST"PROC_SOCKET"
MATERIAL"X6S"
VOLTAGE"4V"
PACK_TYPE"0805"
TOLERANCE"20%"
VALUE"47UF"
PART_NUMBER"C95333-006"
LOCATION"C5P22";
"A"
$PN"1"26;
"B"
$PN"2"23;
%"CAP"
"1","(-5950,900)","0","mstr_discrete","I56";
;
ROOM"PVCCIN_CPU0_DECAP_VR"
CDS_LOCATION"C5P26"
$SEC"1"
CDS_SEC"1"
CDS_LIB"mstr_discrete"
BOM_COST"PROC_SOCKET"
MATERIAL"X6S"
VOLTAGE"4V"
PACK_TYPE"0805"
TOLERANCE"20%"
VALUE"47UF"
PART_NUMBER"C95333-006"
LOCATION"C5P26";
"A"
$PN"1"26;
"B"
$PN"2"23;
%"CAP"
"1","(-6350,925)","0","mstr_discrete","I57";
;
ROOM"PVCCIN_CPU0_DECAP_VR"
CDS_LOCATION"C5P40"
$SEC"1"
CDS_SEC"1"
CDS_LIB"mstr_discrete"
BOM_COST"PROC_SOCKET"
MATERIAL"X6S"
VOLTAGE"4V"
PACK_TYPE"0805"
TOLERANCE"20%"
VALUE"47UF"
PART_NUMBER"C95333-006"
LOCATION"C5P40";
"A"
$PN"1"33;
"B"
$PN"2"30;
%"GND"
"1","(-6350,600)","0","mstr_symbols","I58";
;
HDL_POWER"GND"
BODY_TYPE"PLUMBING"
CDS_LIB"mstr_symbols"
SIZE"1B"
VOLTAGE"0";
"A\NAC"30;
%"CAP"
"1","(-6700,925)","0","mstr_discrete","I59";
;
ROOM"PVCCIN_CPU0_DECAP_VR"
CDS_LOCATION"C5P42"
$SEC"1"
CDS_SEC"1"
CDS_LIB"mstr_discrete"
BOM_COST"PROC_SOCKET"
MATERIAL"X6S"
VOLTAGE"4V"
PACK_TYPE"0805"
TOLERANCE"20%"
VALUE"47UF"
PART_NUMBER"C95333-006"
LOCATION"C5P42";
"A"
$PN"1"33;
"B"
$PN"2"30;
%"CAP"
"1","(-3000,2175)","0","mstr_discrete","I6";
;
ROOM"PVCCIN_CPU0_DECAP_VR"
CDS_LOCATION"C5P10"
$SEC"1"
CDS_SEC"1"
BOM_COST"PROC_SOCKET"
CDS_LIB"mstr_discrete"
MATERIAL"X6S"
VOLTAGE"4V"
PACK_TYPE"0805"
TOLERANCE"20%"
VALUE"47UF"
PART_NUMBER"C95333-006"
LOCATION"C5P10";
"A"
$PN"1"14;
"B"
$PN"2"29;
%"CAP"
"1","(-7050,925)","0","mstr_discrete","I60";
;
ROOM"PVCCIN_CPU0_DECAP_VR"
CDS_LOCATION"C5P43"
$SEC"1"
CDS_SEC"1"
CDS_LIB"mstr_discrete"
BOM_COST"PROC_SOCKET"
MATERIAL"X6S"
VOLTAGE"4V"
PACK_TYPE"0805"
TOLERANCE"20%"
VALUE"47UF"
PART_NUMBER"C95333-006"
LOCATION"C5P43";
"A"
$PN"1"33;
"B"
$PN"2"30;
%"CAP"
"1","(-7375,925)","0","mstr_discrete","I61";
;
ROOM"PVCCIN_CPU0_DECAP_VR"
CDS_LOCATION"C5P44"
$SEC"1"
CDS_SEC"1"
CDS_LIB"mstr_discrete"
BOM_COST"PROC_SOCKET"
MATERIAL"X6S"
VOLTAGE"4V"
PACK_TYPE"0805"
TOLERANCE"20%"
VALUE"47UF"
PART_NUMBER"C95333-006"
LOCATION"C5P44";
"A"
$PN"1"33;
"B"
$PN"2"30;
%"PVCCIN_CPU0"
"1","(-7725,2500)","0","mstr_symbols","I62";
;
HDL_POWER"PVCCIN_CPU0"
BODY_TYPE"PLUMBING"
CDS_LIB"mstr_symbols"
VOLTAGE"2.0V";
"G\NAC"31;
%"CAP"
"1","(-7725,2225)","0","mstr_discrete","I63";
;
ROOM"PVCCIN_CPU0_DECAP_VR"
CDS_LOCATION"C5P37"
$SEC"1"
CDS_SEC"1"
CDS_LIB"mstr_discrete"
BOM_COST"PROC_SOCKET"
VOLTAGE"4V"
MATERIAL"X6S"
PACK_TYPE"0805"
TOLERANCE"20%"
VALUE"47UF"
PART_NUMBER"C95333-006"
LOCATION"C5P37";
"A"
$PN"1"31;
"B"
$PN"2"27;
%"PVCCIN_CPU0"
"1","(-7725,1850)","0","mstr_symbols","I64";
;
HDL_POWER"PVCCIN_CPU0"
BODY_TYPE"PLUMBING"
CDS_LIB"mstr_symbols"
VOLTAGE"2.0V";
"G\NAC"32;
%"CAP"
"1","(-7725,1575)","0","mstr_discrete","I65";
;
ROOM"PVCCIN_CPU0_DECAP_VR"
CDS_LOCATION"C5P36"
$SEC"1"
CDS_SEC"1"
CDS_LIB"mstr_discrete"
BOM_COST"PROC_SOCKET"
MATERIAL"X6S"
VOLTAGE"4V"
PACK_TYPE"0805"
TOLERANCE"20%"
VALUE"47UF"
PART_NUMBER"C95333-006"
LOCATION"C5P36";
"A"
$PN"1"32;
"B"
$PN"2"28;
%"PVCCIN_CPU0"
"1","(-7725,1200)","0","mstr_symbols","I66";
;
HDL_POWER"PVCCIN_CPU0"
BODY_TYPE"PLUMBING"
CDS_LIB"mstr_symbols"
VOLTAGE"2.0V";
"G\NAC"33;
%"CAP_A"
"1","(-800,4450)","0","dev_discrete","I68";
;
ROOM"PVCCIN_CPU0_DECAP_VR"
$SEC"1"
CDS_SEC"1"
CDS_LIB"dev_discrete"
BOM_COST"PROC_SOCKET"
CDS_LOCATION"C6D8"
MATERIAL"X6S"
VOLTAGE"4V"
PACK_TYPE"0603V"
TOLERANCE"20%"
VALUE"22.0UF"
PART_NUMBER"E15431-004"
LOCATION"C6D8";
"B"
$PN"2"34;
"A"
$PN"1"13;
%"CAP_A"
"1","(-1100,4450)","0","dev_discrete","I69";
;
ROOM"PVCCIN_CPU0_DECAP_VR"
$SEC"1"
CDS_SEC"1"
CDS_LIB"dev_discrete"
BOM_COST"PROC_SOCKET"
CDS_LOCATION"C5D38"
MATERIAL"X6S"
VOLTAGE"4V"
PACK_TYPE"0603V"
TOLERANCE"20%"
VALUE"22.0UF"
PART_NUMBER"E15431-004"
LOCATION"C5D38";
"B"
$PN"2"34;
"A"
$PN"1"13;
%"CAP_A"
"1","(-1400,4475)","0","dev_discrete","I70";
;
ROOM"PVCCIN_CPU0_DECAP_VR"
$SEC"1"
CDS_SEC"1"
CDS_LIB"dev_discrete"
BOM_COST"PROC_SOCKET"
CDS_LOCATION"C5D37"
MATERIAL"X6S"
VOLTAGE"4V"
PACK_TYPE"0603V"
TOLERANCE"20%"
VALUE"22.0UF"
PART_NUMBER"E15431-004"
LOCATION"C5D37";
"B"
$PN"2"34;
"A"
$PN"1"13;
%"GND"
"1","(-525,4150)","0","mstr_symbols","I71";
;
HDL_POWER"GND"
BODY_TYPE"PLUMBING"
SIZE"1B"
CDS_LIB"mstr_symbols"
VOLTAGE"0";
"A\NAC"34;
%"CAP_A"
"1","(-3375,3800)","0","dev_discrete","I72";
;
ROOM"PVCCIN_CPU0_DECAP_VR"
$SEC"1"
CDS_SEC"1"
CDS_LIB"dev_discrete"
BOM_COST"PROC_SOCKET"
CDS_LOCATION"C6D7"
MATERIAL"X6S"
VOLTAGE"4V"
PACK_TYPE"0603V"
TOLERANCE"20%"
VALUE"22.0UF"
PART_NUMBER"E15431-004"
LOCATION"C6D7";
"B"
$PN"2"35;
"A"
$PN"1"36;
%"GND"
"1","(-2850,3500)","0","mstr_symbols","I73";
;
HDL_POWER"GND"
BODY_TYPE"PLUMBING"
SIZE"1B"
CDS_LIB"mstr_symbols"
VOLTAGE"0";
"A\NAC"35;
%"CAP_A"
"1","(-3600,3800)","0","dev_discrete","I74";
;
ROOM"PVCCIN_CPU0_DECAP_VR"
$SEC"1"
CDS_SEC"1"
CDS_LIB"dev_discrete"
BOM_COST"PROC_SOCKET"
CDS_LOCATION"C6D4"
MATERIAL"X6S"
VOLTAGE"4V"
PACK_TYPE"0603V"
TOLERANCE"20%"
VALUE"22.0UF"
PART_NUMBER"E15431-004"
LOCATION"C6D4";
"B"
$PN"2"35;
"A"
$PN"1"36;
%"CAP_A"
"1","(-1700,4450)","0","dev_discrete","I75";
;
ROOM"PVCCIN_CPU0_DECAP_VR"
$SEC"1"
CDS_SEC"1"
CDS_LIB"dev_discrete"
BOM_COST"PROC_SOCKET"
CDS_LOCATION"C6D5"
MATERIAL"X6S"
VOLTAGE"4V"
PACK_TYPE"0603V"
TOLERANCE"20%"
VALUE"22.0UF"
PART_NUMBER"E15431-004"
LOCATION"C6D5";
"B"
$PN"2"34;
"A"
$PN"1"13;
%"CAP_A"
"1","(-2000,4475)","0","dev_discrete","I77";
;
ROOM"PVCCIN_CPU0_DECAP_VR"
$SEC"1"
CDS_SEC"1"
CDS_LIB"dev_discrete"
BOM_COST"PROC_SOCKET"
CDS_LOCATION"C6D2"
MATERIAL"X6S"
VOLTAGE"4V"
PACK_TYPE"0603V"
TOLERANCE"20%"
VALUE"22.0UF"
PART_NUMBER"E15431-004"
LOCATION"C6D2";
"B"
$PN"2"34;
"A"
$PN"1"13;
%"PVCCIO_CPU0"
"1","(-4075,4075)","0","mstr_symbols","I79";
;
HDL_POWER"PVCCIO_CPU0"
BODY_TYPE"PLUMBING"
CDS_LIB"mstr_symbols"
VOLTAGE"1.1V";
"G\NAC"36;
%"CAP"
"1","(-3275,2175)","0","mstr_discrete","I8";
;
ROOM"PVCCIN_CPU0_DECAP_VR"
CDS_LOCATION"C4P3"
$SEC"1"
CDS_SEC"1"
BOM_COST"PROC_SOCKET"
CDS_LIB"mstr_discrete"
MATERIAL"X6S"
VOLTAGE"4V"
PACK_TYPE"0805"
TOLERANCE"20%"
VALUE"47UF"
PART_NUMBER"C95333-006"
LOCATION"C4P3";
"A"
$PN"1"14;
"B"
$PN"2"29;
%"CAP_A"
"1","(-3825,3800)","0","dev_discrete","I80";
;
ROOM"PVCCIN_CPU0_DECAP_VR"
$SEC"1"
CDS_SEC"1"
CDS_LIB"dev_discrete"
BOM_COST"PROC_SOCKET"
CDS_LOCATION"C6D3"
MATERIAL"X6S"
VOLTAGE"4V"
PACK_TYPE"0603V"
TOLERANCE"20%"
VALUE"22.0UF"
PART_NUMBER"E15431-004"
LOCATION"C6D3";
"B"
$PN"2"35;
"A"
$PN"1"36;
%"CAP_A"
"1","(-4075,3775)","0","dev_discrete","I81";
;
ROOM"PVCCIN_CPU0_DECAP_VR"
$SEC"1"
CDS_SEC"1"
CDS_LIB"dev_discrete"
BOM_COST"PROC_SOCKET"
CDS_LOCATION"C6D6"
MATERIAL"X6S"
VOLTAGE"4V"
PACK_TYPE"0603V"
TOLERANCE"20%"
VALUE"22.0UF"
PART_NUMBER"E15431-004"
LOCATION"C6D6";
"B"
$PN"2"35;
"A"
$PN"1"36;
%"CAP_A"
"1","(-2825,4475)","0","dev_discrete","I83";
;
ROOM"PVCCIN_CPU0_DECAP_VR"
$SEC"1"
CDS_SEC"1"
CDS_LIB"dev_discrete"
BOM_COST"PROC_SOCKET"
CDS_LOCATION"C5D51"
MATERIAL"X6S"
VOLTAGE"4V"
PACK_TYPE"0603V"
TOLERANCE"20%"
VALUE"22.0UF"
PART_NUMBER"E15431-004"
LOCATION"C5D51";
"B"
$PN"2"34;
"A"
$PN"1"13;
%"CAP_A"
"1","(-3075,4450)","0","dev_discrete","I88";
;
ROOM"PVCCIN_CPU0_DECAP_VR"
$SEC"1"
CDS_SEC"1"
CDS_LIB"dev_discrete"
BOM_COST"PROC_SOCKET"
CDS_LOCATION"C5D21"
MATERIAL"X6S"
VOLTAGE"4V"
PACK_TYPE"0603V"
TOLERANCE"20%"
VALUE"22.0UF"
PART_NUMBER"E15431-004"
LOCATION"C5D21";
"B"
$PN"2"34;
"A"
$PN"1"13;
%"CAP_A"
"1","(-3350,4475)","0","dev_discrete","I89";
;
ROOM"PVCCIN_CPU0_DECAP_VR"
$SEC"1"
CDS_SEC"1"
CDS_LIB"dev_discrete"
BOM_COST"PROC_SOCKET"
CDS_LOCATION"C5D50"
MATERIAL"X6S"
VOLTAGE"4V"
PACK_TYPE"0603V"
TOLERANCE"20%"
VALUE"22.0UF"
PART_NUMBER"E15431-004"
LOCATION"C5D50";
"B"
$PN"2"34;
"A"
$PN"1"13;
%"CAP"
"1","(-3550,2175)","0","mstr_discrete","I9";
;
ROOM"PVCCIN_CPU0_DECAP_VR"
CDS_LOCATION"C4P7"
$SEC"1"
CDS_SEC"1"
BOM_COST"PROC_SOCKET"
CDS_LIB"mstr_discrete"
MATERIAL"X6S"
VOLTAGE"4V"
PACK_TYPE"0805"
TOLERANCE"20%"
VALUE"47UF"
PART_NUMBER"C95333-006"
LOCATION"C4P7";
"A"
$PN"1"14;
"B"
$PN"2"29;
%"CAP_A"
"1","(-3625,4475)","0","dev_discrete","I90";
;
ROOM"PVCCIN_CPU0_DECAP_VR"
$SEC"1"
CDS_SEC"1"
CDS_LIB"dev_discrete"
BOM_COST"PROC_SOCKET"
CDS_LOCATION"C5D48"
MATERIAL"X6S"
VOLTAGE"4V"
PACK_TYPE"0603V"
TOLERANCE"20%"
VALUE"22.0UF"
PART_NUMBER"E15431-004"
LOCATION"C5D48";
"B"
$PN"2"34;
"A"
$PN"1"13;
%"CAP"
"1","(-2875,3125)","0","mstr_discrete","I91";
;
ROOM"PVCCIN_CPU0_DECAP_VR"
CDS_LOCATION"C5D13"
$SEC"1"
CDS_SEC"1"
BOM_COST"PROC_SOCKET"
CDS_LIB"mstr_discrete"
MATERIAL"X6S"
VOLTAGE"4V"
PACK_TYPE"0603LF"
TOLERANCE"20%"
VALUE"10UF"
PART_NUMBER"E15431-001"
LOCATION"C5D13";
"A"
$PN"1"38;
"B"
$PN"2"37;
%"GND"
"1","(-2875,2800)","0","mstr_symbols","I92";
;
HDL_POWER"GND"
BODY_TYPE"PLUMBING"
SIZE"1B"
CDS_LIB"mstr_symbols"
VOLTAGE"0";
"A\NAC"37;
%"CAP"
"1","(-3275,3125)","0","mstr_discrete","I93";
;
ROOM"PVCCIN_CPU0_DECAP_VR"
CDS_LOCATION"C5D11"
$SEC"1"
CDS_SEC"1"
BOM_COST"PROC_SOCKET"
CDS_LIB"mstr_discrete"
MATERIAL"X6S"
VOLTAGE"4V"
PACK_TYPE"0603LF"
TOLERANCE"20%"
VALUE"10UF"
PART_NUMBER"E15431-001"
LOCATION"C5D11";
"A"
$PN"1"38;
"B"
$PN"2"37;
%"CAP"
"1","(-3675,3150)","0","mstr_discrete","I94";
;
ROOM"PVCCIN_CPU0_DECAP_VR"
CDS_LOCATION"C5D12"
$SEC"1"
CDS_SEC"1"
BOM_COST"PROC_SOCKET"
CDS_LIB"mstr_discrete"
MATERIAL"X6S"
VOLTAGE"4V"
PACK_TYPE"0603LF"
TOLERANCE"20%"
VALUE"10UF"
PART_NUMBER"E15431-001"
LOCATION"C5D12";
"A"
$PN"1"38;
"B"
$PN"2"37;
%"CAP_A"
"1","(-3875,4475)","0","dev_discrete","I98";
;
ROOM"PVCCIN_CPU0_DECAP_VR"
$SEC"1"
CDS_SEC"1"
CDS_LIB"dev_discrete"
BOM_COST"PROC_SOCKET"
CDS_LOCATION"C5D23"
MATERIAL"X6S"
VOLTAGE"4V"
PACK_TYPE"0603V"
TOLERANCE"20%"
VALUE"22.0UF"
PART_NUMBER"E15431-004"
LOCATION"C5D23";
"B"
$PN"2"34;
"A"
$PN"1"13;
%"PVSA_CPU0"
"1","(-4075,3400)","0","mstr_symbols","I99";
;
HDL_POWER"PVSA_CPU0"
BODY_TYPE"PLUMBING"
CDS_LIB"mstr_symbols"
VOLTAGE"1.1V";
"G\NAC"38;
END.
